FILE_TYPE=LIBRARY_PARTS;
primitive 'TTL1G32_A', 'TTL1G32_A_DE_SOT';
  pin
    'A':
      PIN_NUMBER='(1)';
      INPUT_LOAD='(-0.6,0.02)';
      PIN_GROUP='1';  
    'B':
      PIN_NUMBER='(2)';
      INPUT_LOAD='(-0.6,0.02)';
      PIN_GROUP='1';
    'Y':  
      PIN_NUMBER='(4)';
      OUTPUT_LOAD='(20.0,-1.0)';      
  end_pin;
  body
    POWER_PINS='(VCC:5;GND:3)';
    PART_NAME='TTL1G32_A';
    PHYS_DES_PREFIX='U';
  end_body;
end_primitive;
END.
